FILE_TYPE = CONNECTIVITY;
{Allegro Design Entry HDL 17.4-2019 S026 (4007227) 1/17/2022}
"PAGE_NUMBER" = 134;
0"NC";
END.
